# BASEBOARD_FAB2 (Tioga Pass) — schematic netlist excerpt (pin names and nets, part order shuffled) for the footprints in the layout excerpt that follows; sources: Cadence DE-HDL packaged netlist, KiCad conversion of Wiwynn_Tioga_Pass_MB.brd

R8D17  RES  1.37K 1% CHIP  pkg 0402  page 138 : A = P3V3_STBY ; B = SMB_VR_STBY_LVC3_SDA

(kicad_pcb
	(version 20260206)
	(generator "pcbnew")
	(generator_version "10.0")
	(general
		(thickness 1.6)
		(legacy_teardrops no)
	)
	(paper "A4")
	(title_block
		(title "Wiwynn_Tioga_Pass_MB.brd")
		(comment 1 "Tioga Pass / footprints 2837-2837 of 4770")
	)
	(layers
		(0 "F.Cu" signal "TOP")
		(4 "In1.Cu" signal "L2GND")
		(6 "In2.Cu" signal "L3")
		(8 "In3.Cu" signal "L4GND")
		(10 "In4.Cu" signal "L5")
		(12 "In5.Cu" signal "L6GND")
		(14 "In6.Cu" signal "L7VCC")
		(16 "In7.Cu" signal "L8VCC")
		(18 "In8.Cu" signal "L9GND")
		(20 "In9.Cu" signal "L10")
		(22 "In10.Cu" signal "L11GND")
		(24 "In11.Cu" signal "L12")
		(26 "In12.Cu" signal "L13GND")
		(2 "B.Cu" signal "BOTTOM")
		(9 "F.Adhes" user "F.Adhesive")
		(11 "B.Adhes" user "B.Adhesive")
		(13 "F.Paste" user "Package Geometry/Pastemask Top")
		(15 "B.Paste" user "Package Geometry/Pastemask Bottom")
		(5 "F.SilkS" user "Ref Des/Silkscreen Top")
		(7 "B.SilkS" user "Ref Des/Silkscreen Bottom")
		(1 "F.Mask" user "Board Geometry/Soldermask Top")
		(3 "B.Mask" user "Board Geometry/Soldermask Bottom")
		(17 "Dwgs.User" user "User.Drawings")
		(19 "Cmts.User" user "User.Comments")
		(21 "Eco1.User" user "User.Eco1")
		(23 "Eco2.User" user "User.Eco2")
		(25 "Edge.Cuts" user "Board Geometry/Outline")
		(27 "Margin" user)
		(31 "F.CrtYd" user "Package Geometry/Place Bound Top")
		(29 "B.CrtYd" user "Package Geometry/Place Bound Bottom")
		(35 "F.Fab" user "Ref Des/Assembly Top")
		(33 "B.Fab" user "Ref Des/Assembly Bottom")
	)
	(footprint ""
		(layer "B.Cu")
		(at 397.764 -85.0265 180)
		(property "Reference" "R8D17"
			(at 0.8382 -0.67818 180)
			(unlocked yes)
			(layer "B.SilkS")
			(effects
				(font
					(size 0.4064 0.254)
					(thickness 0.1524)
				)
				(justify left mirror)
			)
		)
		(property "Value" ""
			(at 0 0 0)
			(layer "B.Fab")
			(effects
				(font
					(size 1.27 1.27)
				)
				(justify mirror)
			)
		)
		(duplicate_pad_numbers_are_jumpers no)
		(fp_poly
			(pts
				(xy 0.2794 -0.1016) (xy -0.2794 -0.1016) (xy -0.2794 0.9906) (xy 0.2794 0.9906)
			)
			(stroke
				(width 0)
				(type default)
			)
			(fill no)
			(layer "B.CrtYd")
		)
		(fp_line
			(start 0.2794 0.9906)
			(end -0.2794 0.9906)
			(stroke
				(width 0.1)
				(type default)
			)
			(layer "B.Fab")
		)
		(fp_line
			(start 0.2794 -0.1016)
			(end 0.2794 0.9906)
			(stroke
				(width 0.1)
				(type default)
			)
			(layer "B.Fab")
		)
		(fp_line
			(start -0.2794 0.9906)
			(end -0.2794 -0.1016)
			(stroke
				(width 0.1)
				(type default)
			)
			(layer "B.Fab")
		)
		(fp_line
			(start -0.2794 -0.1016)
			(end 0.2794 -0.1016)
			(stroke
				(width 0.1)
				(type default)
			)
			(layer "B.Fab")
		)
		(pad "1" smd rect
			(at 0 0)
			(size 0.508 0.508)
			(layers "B.Cu" "B.Mask" "B.Paste")
			(net "P3V3_STBY")
		)
		(pad "2" smd rect
			(at 0 0.889)
			(size 0.508 0.508)
			(layers "B.Cu" "B.Mask" "B.Paste")
			(net "SMB_VR_STBY_LVC3_SDA")
		)
		(zone
			(layer "B.Cu")
			(hatch none 0.5)
			(connect_pads
				(clearance 0)
			)
			(min_thickness 0.25)
			(keepout
				(tracks not_allowed)
				(vias allowed)
				(pads allowed)
				(copperpour not_allowed)
				(footprints allowed)
			)
			(placement
				(enabled no)
				(sheetname "")
			)
			(fill
				(thermal_gap 0.5)
				(thermal_bridge_width 0.5)
				(island_removal_mode 0)
			)
			(polygon
				(pts
					(xy 397.51 -85.6615) (xy 398.018 -85.6615) (xy 398.018 -85.2805) (xy 397.51 -85.2805)
				)
			)
		)
		(zone
			(layer "B.Cu")
			(hatch none 0.5)
			(connect_pads
				(clearance 0)
			)
			(min_thickness 0.25)
			(keepout
				(tracks allowed)
				(vias not_allowed)
				(pads allowed)
				(copperpour not_allowed)
				(footprints allowed)
			)
			(placement
				(enabled no)
				(sheetname "")
			)
			(fill
				(thermal_gap 0.5)
				(thermal_bridge_width 0.5)
				(island_removal_mode 0)
			)
			(polygon
				(pts
					(xy 397.51 -85.2805) (xy 398.018 -85.2805) (xy 398.018 -85.6615) (xy 397.51 -85.6615)
				)
			)
		)
	)
)
